(kicad_pcb
	(version 20260206)
	(generator "pcbnew")
	(generator_version "10.0")
	(general
		(thickness 1.6)
		(legacy_teardrops no)
	)
	(paper "A4")
	(title_block
		(title "04192023_DAF0TMB3IC0_F0TG_MB_C_brd_V02_OCP.brd")
		(comment 1 "Grand Teton / footprints 111-118 of 8354")
	)
	(layers
		(0 "F.Cu" signal "TOP")
		(4 "In1.Cu" signal "GND")
		(6 "In2.Cu" signal "IN1")
		(8 "In3.Cu" signal "GND1")
		(10 "In4.Cu" signal "IN2")
		(12 "In5.Cu" signal "GND2")
		(14 "In6.Cu" signal "IN3")
		(16 "In7.Cu" signal "GND3")
		(18 "In8.Cu" signal "VCC")
		(20 "In9.Cu" signal "VCC1")
		(22 "In10.Cu" signal "GND4")
		(24 "In11.Cu" signal "IN4")
		(26 "In12.Cu" signal "GND5")
		(28 "In13.Cu" signal "IN5")
		(30 "In14.Cu" signal "GND6")
		(32 "In15.Cu" signal "IN6")
		(34 "In16.Cu" signal "GND7")
		(2 "B.Cu" signal "BOTTOM")
		(9 "F.Adhes" user "F.Adhesive")
		(11 "B.Adhes" user "B.Adhesive")
		(13 "F.Paste" user "Package Geometry/Pastemask Top")
		(15 "B.Paste" user "Package Geometry/Pastemask Bottom")
		(5 "F.SilkS" user "Ref Des/Silkscreen Top")
		(7 "B.SilkS" user "Ref Des/Silkscreen Bottom")
		(1 "F.Mask" user "Board Geometry/Soldermask Top")
		(3 "B.Mask" user "Board Geometry/Soldermask Bottom")
		(17 "Dwgs.User" user "User.Drawings")
		(19 "Cmts.User" user "User.Comments")
		(21 "Eco1.User" user "User.Eco1")
		(23 "Eco2.User" user "User.Eco2")
		(25 "Edge.Cuts" user "Board Geometry/Outline")
		(27 "Margin" user)
		(31 "F.CrtYd" user "Package Geometry/Place Bound Top")
		(29 "B.CrtYd" user "Package Geometry/Place Bound Bottom")
		(35 "F.Fab" user "Ref Des/Assembly Top")
		(33 "B.Fab" user "Ref Des/Assembly Bottom")
	)
	(footprint ""
		(layer "F.Cu")
		(at 82.437478 -335.134458 -90)
		(property "Reference" "PC378_2"
			(at 0 0 270)
			(layer "F.SilkS")
			(hide yes)
			(effects
				(font
					(size 1.27 1.27)
				)
			)
		)
		(property "Value" ""
			(at 0 0 270)
			(layer "F.Fab")
			(effects
				(font
					(size 1.27 1.27)
				)
			)
		)
		(duplicate_pad_numbers_are_jumpers no)
		(fp_line
			(start -0.7874 0.4064)
			(end -0.7874 -0.4064)
			(stroke
				(width 0.1524)
				(type default)
			)
			(layer "F.SilkS")
		)
		(fp_line
			(start 0.7874 0.4064)
			(end -0.7874 0.4064)
			(stroke
				(width 0.1524)
				(type default)
			)
			(layer "F.SilkS")
		)
		(fp_line
			(start -0.7874 -0.4064)
			(end 0.7874 -0.4064)
			(stroke
				(width 0.1524)
				(type default)
			)
			(layer "F.SilkS")
		)
		(fp_line
			(start 0.7874 -0.4064)
			(end 0.7874 0.4064)
			(stroke
				(width 0.1524)
				(type default)
			)
			(layer "F.SilkS")
		)
		(fp_line
			(start -0.67945 0.3048)
			(end -0.67945 -0.305054)
			(stroke
				(width 0.1)
				(type default)
			)
			(layer "F.Fab")
		)
		(fp_line
			(start -0.12065 0.3048)
			(end -0.67945 0.3048)
			(stroke
				(width 0.1)
				(type default)
			)
			(layer "F.Fab")
		)
		(fp_line
			(start 0.120396 0.3048)
			(end 0.120396 0.2794)
			(stroke
				(width 0.1)
				(type default)
			)
			(layer "F.Fab")
		)
		(fp_line
			(start 0.67945 0.3048)
			(end 0.120396 0.3048)
			(stroke
				(width 0.1)
				(type default)
			)
			(layer "F.Fab")
		)
		(fp_line
			(start -0.12065 0.2794)
			(end -0.12065 0.3048)
			(stroke
				(width 0.1)
				(type default)
			)
			(layer "F.Fab")
		)
		(fp_line
			(start 0.120396 0.2794)
			(end -0.12065 0.2794)
			(stroke
				(width 0.1)
				(type default)
			)
			(layer "F.Fab")
		)
		(fp_line
			(start -0.12065 -0.2794)
			(end 0.12065 -0.2794)
			(stroke
				(width 0.1)
				(type default)
			)
			(layer "F.Fab")
		)
		(fp_line
			(start 0.12065 -0.2794)
			(end 0.12065 -0.3048)
			(stroke
				(width 0.1)
				(type default)
			)
			(layer "F.Fab")
		)
		(fp_line
			(start 0.12065 -0.3048)
			(end 0.67945 -0.3048)
			(stroke
				(width 0.1)
				(type default)
			)
			(layer "F.Fab")
		)
		(fp_line
			(start 0.67945 -0.3048)
			(end 0.67945 0.3048)
			(stroke
				(width 0.1)
				(type default)
			)
			(layer "F.Fab")
		)
		(fp_line
			(start -0.67945 -0.305054)
			(end -0.12065 -0.305054)
			(stroke
				(width 0.1)
				(type default)
			)
			(layer "F.Fab")
		)
		(fp_line
			(start -0.12065 -0.305054)
			(end -0.12065 -0.2794)
			(stroke
				(width 0.1)
				(type default)
			)
			(layer "F.Fab")
		)
		(pad "1" smd circle
			(at -0.40005 0 270)
			(size 0 0)
			(layers "F.Cu" "F.Mask" "F.Paste")
			(net "SW_P12V_AUX_PVDDCR_CPU1_P1_FLT")
		)
		(pad "2" smd circle
			(at 0.40005 0 270)
			(size 0 0)
			(layers "F.Cu" "F.Mask" "F.Paste")
			(net "GND")
		)
	)
	(footprint ""
		(layer "F.Cu")
		(at 297.554142 -399.034)
		(property "Reference" "R1001"
			(at 0 0 0)
			(layer "F.SilkS")
			(hide yes)
			(effects
				(font
					(size 1.27 1.27)
				)
			)
		)
		(property "Value" ""
			(at 0 0 0)
			(layer "F.Fab")
			(effects
				(font
					(size 1.27 1.27)
				)
			)
		)
		(duplicate_pad_numbers_are_jumpers no)
		(fp_line
			(start -0.32512 -0.175006)
			(end 0.32512 -0.175006)
			(stroke
				(width 0.1)
				(type default)
			)
			(layer "F.Fab")
		)
		(fp_line
			(start -0.32512 0.175006)
			(end -0.32512 -0.175006)
			(stroke
				(width 0.1)
				(type default)
			)
			(layer "F.Fab")
		)
		(fp_line
			(start 0.32512 -0.175006)
			(end 0.32512 0.175006)
			(stroke
				(width 0.1)
				(type default)
			)
			(layer "F.Fab")
		)
		(fp_line
			(start 0.32512 0.175006)
			(end -0.32512 0.175006)
			(stroke
				(width 0.1)
				(type default)
			)
			(layer "F.Fab")
		)
		(pad "1" smd rect
			(at -0.2667 0)
			(size 0.3048 0.381)
			(layers "F.Cu" "F.Mask" "F.Paste")
			(net "MODE_RT_CPU0_P0")
		)
		(pad "2" smd rect
			(at 0.2667 0 180)
			(size 0.3048 0.381)
			(layers "F.Cu" "F.Mask" "F.Paste")
			(net "GND")
		)
	)
	(footprint ""
		(layer "F.Cu")
		(at 101.509068 -394.3604 -90)
		(property "Reference" "R6732"
			(at 0 0 270)
			(layer "F.SilkS")
			(hide yes)
			(effects
				(font
					(size 1.27 1.27)
				)
			)
		)
		(property "Value" ""
			(at 0 0 270)
			(layer "F.Fab")
			(effects
				(font
					(size 1.27 1.27)
				)
			)
		)
		(duplicate_pad_numbers_are_jumpers no)
		(fp_line
			(start -0.32512 0.175006)
			(end -0.32512 -0.175006)
			(stroke
				(width 0.1)
				(type default)
			)
			(layer "F.Fab")
		)
		(fp_line
			(start 0.32512 0.175006)
			(end -0.32512 0.175006)
			(stroke
				(width 0.1)
				(type default)
			)
			(layer "F.Fab")
		)
		(fp_line
			(start -0.32512 -0.175006)
			(end 0.32512 -0.175006)
			(stroke
				(width 0.1)
				(type default)
			)
			(layer "F.Fab")
		)
		(fp_line
			(start 0.32512 -0.175006)
			(end 0.32512 0.175006)
			(stroke
				(width 0.1)
				(type default)
			)
			(layer "F.Fab")
		)
		(pad "1" smd rect
			(at -0.2667 0 270)
			(size 0.3048 0.381)
			(layers "F.Cu" "F.Mask" "F.Paste")
			(net "NCF_A1_CPU1_P1_GND")
		)
		(pad "2" smd rect
			(at 0.2667 0 90)
			(size 0.3048 0.381)
			(layers "F.Cu" "F.Mask" "F.Paste")
			(net "GND")
		)
	)
	(footprint ""
		(layer "F.Cu")
		(at 138.981942 -386.7912 90)
		(property "Reference" "R903"
			(at 0 0 90)
			(layer "F.SilkS")
			(hide yes)
			(effects
				(font
					(size 1.27 1.27)
				)
			)
		)
		(property "Value" ""
			(at 0 0 90)
			(layer "F.Fab")
			(effects
				(font
					(size 1.27 1.27)
				)
			)
		)
		(duplicate_pad_numbers_are_jumpers no)
		(fp_line
			(start 0.32512 -0.175006)
			(end 0.32512 0.175006)
			(stroke
				(width 0.1)
				(type default)
			)
			(layer "F.Fab")
		)
		(fp_line
			(start -0.32512 -0.175006)
			(end 0.32512 -0.175006)
			(stroke
				(width 0.1)
				(type default)
			)
			(layer "F.Fab")
		)
		(fp_line
			(start 0.32512 0.175006)
			(end -0.32512 0.175006)
			(stroke
				(width 0.1)
				(type default)
			)
			(layer "F.Fab")
		)
		(fp_line
			(start -0.32512 0.175006)
			(end -0.32512 -0.175006)
			(stroke
				(width 0.1)
				(type default)
			)
			(layer "F.Fab")
		)
		(pad "1" smd rect
			(at -0.2667 0 90)
			(size 0.3048 0.381)
			(layers "F.Cu" "F.Mask" "F.Paste")
			(net "RT_CPU1_P3_ADDR3")
		)
		(pad "2" smd rect
			(at 0.2667 0 270)
			(size 0.3048 0.381)
			(layers "F.Cu" "F.Mask" "F.Paste")
			(net "GND")
		)
	)
	(footprint ""
		(layer "F.Cu")
		(at 369.455446 -28.306522 90)
		(property "Reference" "R822"
			(at 0 0 90)
			(layer "F.SilkS")
			(hide yes)
			(effects
				(font
					(size 1.27 1.27)
				)
			)
		)
		(property "Value" ""
			(at 0 0 90)
			(layer "F.Fab")
			(effects
				(font
					(size 1.27 1.27)
				)
			)
		)
		(duplicate_pad_numbers_are_jumpers no)
		(fp_line
			(start 0.7874 -0.4064)
			(end 0.7874 0.4064)
			(stroke
				(width 0.1524)
				(type default)
			)
			(layer "F.SilkS")
		)
		(fp_line
			(start -0.7874 -0.4064)
			(end 0.7874 -0.4064)
			(stroke
				(width 0.1524)
				(type default)
			)
			(layer "F.SilkS")
		)
		(fp_line
			(start 0.7874 0.4064)
			(end -0.7874 0.4064)
			(stroke
				(width 0.1524)
				(type default)
			)
			(layer "F.SilkS")
		)
		(fp_line
			(start -0.7874 0.4064)
			(end -0.7874 -0.4064)
			(stroke
				(width 0.1524)
				(type default)
			)
			(layer "F.SilkS")
		)
		(fp_line
			(start -0.12065 -0.305054)
			(end -0.12065 -0.2794)
			(stroke
				(width 0.1)
				(type default)
			)
			(layer "F.Fab")
		)
		(fp_line
			(start -0.67945 -0.305054)
			(end -0.12065 -0.305054)
			(stroke
				(width 0.1)
				(type default)
			)
			(layer "F.Fab")
		)
		(fp_line
			(start 0.67945 -0.3048)
			(end 0.67945 0.3048)
			(stroke
				(width 0.1)
				(type default)
			)
			(layer "F.Fab")
		)
		(fp_line
			(start 0.12065 -0.3048)
			(end 0.67945 -0.3048)
			(stroke
				(width 0.1)
				(type default)
			)
			(layer "F.Fab")
		)
		(fp_line
			(start 0.12065 -0.2794)
			(end 0.12065 -0.3048)
			(stroke
				(width 0.1)
				(type default)
			)
			(layer "F.Fab")
		)
		(fp_line
			(start -0.12065 -0.2794)
			(end 0.12065 -0.2794)
			(stroke
				(width 0.1)
				(type default)
			)
			(layer "F.Fab")
		)
		(fp_line
			(start 0.120396 0.2794)
			(end -0.12065 0.2794)
			(stroke
				(width 0.1)
				(type default)
			)
			(layer "F.Fab")
		)
		(fp_line
			(start -0.12065 0.2794)
			(end -0.12065 0.3048)
			(stroke
				(width 0.1)
				(type default)
			)
			(layer "F.Fab")
		)
		(fp_line
			(start 0.67945 0.3048)
			(end 0.120396 0.3048)
			(stroke
				(width 0.1)
				(type default)
			)
			(layer "F.Fab")
		)
		(fp_line
			(start 0.120396 0.3048)
			(end 0.120396 0.2794)
			(stroke
				(width 0.1)
				(type default)
			)
			(layer "F.Fab")
		)
		(fp_line
			(start -0.12065 0.3048)
			(end -0.67945 0.3048)
			(stroke
				(width 0.1)
				(type default)
			)
			(layer "F.Fab")
		)
		(fp_line
			(start -0.67945 0.3048)
			(end -0.67945 -0.305054)
			(stroke
				(width 0.1)
				(type default)
			)
			(layer "F.Fab")
		)
		(pad "1" smd circle
			(at -0.40005 0 90)
			(size 0 0)
			(layers "F.Cu" "F.Mask" "F.Paste")
			(net "P3V3_AUX")
		)
		(pad "2" smd circle
			(at 0.40005 0 90)
			(size 0 0)
			(layers "F.Cu" "F.Mask" "F.Paste")
			(net "UART_CPU0_SCM_LVC3_UART1_TX")
		)
	)
	(footprint ""
		(layer "F.Cu")
		(at 183.007 -129.377948 -90)
		(property "Reference" "R241"
			(at 0 0 270)
			(layer "F.SilkS")
			(hide yes)
			(effects
				(font
					(size 1.27 1.27)
				)
			)
		)
		(property "Value" ""
			(at 0 0 270)
			(layer "F.Fab")
			(effects
				(font
					(size 1.27 1.27)
				)
			)
		)
		(duplicate_pad_numbers_are_jumpers no)
		(fp_line
			(start -0.7874 0.4064)
			(end -0.7874 -0.4064)
			(stroke
				(width 0.1524)
				(type default)
			)
			(layer "F.SilkS")
		)
		(fp_line
			(start 0.7874 0.4064)
			(end -0.7874 0.4064)
			(stroke
				(width 0.1524)
				(type default)
			)
			(layer "F.SilkS")
		)
		(fp_line
			(start -0.7874 -0.4064)
			(end 0.7874 -0.4064)
			(stroke
				(width 0.1524)
				(type default)
			)
			(layer "F.SilkS")
		)
		(fp_line
			(start 0.7874 -0.4064)
			(end 0.7874 0.4064)
			(stroke
				(width 0.1524)
				(type default)
			)
			(layer "F.SilkS")
		)
		(fp_line
			(start -0.67945 0.3048)
			(end -0.67945 -0.305054)
			(stroke
				(width 0.1)
				(type default)
			)
			(layer "F.Fab")
		)
		(fp_line
			(start -0.12065 0.3048)
			(end -0.67945 0.3048)
			(stroke
				(width 0.1)
				(type default)
			)
			(layer "F.Fab")
		)
		(fp_line
			(start 0.120396 0.3048)
			(end 0.120396 0.2794)
			(stroke
				(width 0.1)
				(type default)
			)
			(layer "F.Fab")
		)
		(fp_line
			(start 0.67945 0.3048)
			(end 0.120396 0.3048)
			(stroke
				(width 0.1)
				(type default)
			)
			(layer "F.Fab")
		)
		(fp_line
			(start -0.12065 0.2794)
			(end -0.12065 0.3048)
			(stroke
				(width 0.1)
				(type default)
			)
			(layer "F.Fab")
		)
		(fp_line
			(start 0.120396 0.2794)
			(end -0.12065 0.2794)
			(stroke
				(width 0.1)
				(type default)
			)
			(layer "F.Fab")
		)
		(fp_line
			(start -0.12065 -0.2794)
			(end 0.12065 -0.2794)
			(stroke
				(width 0.1)
				(type default)
			)
			(layer "F.Fab")
		)
		(fp_line
			(start 0.12065 -0.2794)
			(end 0.12065 -0.3048)
			(stroke
				(width 0.1)
				(type default)
			)
			(layer "F.Fab")
		)
		(fp_line
			(start 0.12065 -0.3048)
			(end 0.67945 -0.3048)
			(stroke
				(width 0.1)
				(type default)
			)
			(layer "F.Fab")
		)
		(fp_line
			(start 0.67945 -0.3048)
			(end 0.67945 0.3048)
			(stroke
				(width 0.1)
				(type default)
			)
			(layer "F.Fab")
		)
		(fp_line
			(start -0.67945 -0.305054)
			(end -0.12065 -0.305054)
			(stroke
				(width 0.1)
				(type default)
			)
			(layer "F.Fab")
		)
		(fp_line
			(start -0.12065 -0.305054)
			(end -0.12065 -0.2794)
			(stroke
				(width 0.1)
				(type default)
			)
			(layer "F.Fab")
		)
		(pad "1" smd circle
			(at -0.40005 0 270)
			(size 0 0)
			(layers "F.Cu" "F.Mask" "F.Paste")
			(net "RST_CPU0_RESETL_N")
		)
		(pad "2" smd circle
			(at 0.40005 0 270)
			(size 0 0)
			(layers "F.Cu" "F.Mask" "F.Paste")
			(net "FM_RST_CPU0_RESETL_N")
		)
	)
	(footprint ""
		(layer "F.Cu")
		(at 439.072782 -435.27726 -90)
		(property "Reference" "R3470"
			(at 0 0 270)
			(layer "F.SilkS")
			(hide yes)
			(effects
				(font
					(size 1.27 1.27)
				)
			)
		)
		(property "Value" ""
			(at 0 0 270)
			(layer "F.Fab")
			(effects
				(font
					(size 1.27 1.27)
				)
			)
		)
		(duplicate_pad_numbers_are_jumpers no)
		(fp_line
			(start -0.7874 0.4064)
			(end -0.7874 -0.4064)
			(stroke
				(width 0.1524)
				(type default)
			)
			(layer "F.SilkS")
		)
		(fp_line
			(start 0.7874 0.4064)
			(end -0.7874 0.4064)
			(stroke
				(width 0.1524)
				(type default)
			)
			(layer "F.SilkS")
		)
		(fp_line
			(start -0.7874 -0.4064)
			(end 0.7874 -0.4064)
			(stroke
				(width 0.1524)
				(type default)
			)
			(layer "F.SilkS")
		)
		(fp_line
			(start 0.7874 -0.4064)
			(end 0.7874 0.4064)
			(stroke
				(width 0.1524)
				(type default)
			)
			(layer "F.SilkS")
		)
		(fp_line
			(start -0.67945 0.3048)
			(end -0.67945 -0.305054)
			(stroke
				(width 0.1)
				(type default)
			)
			(layer "F.Fab")
		)
		(fp_line
			(start -0.12065 0.3048)
			(end -0.67945 0.3048)
			(stroke
				(width 0.1)
				(type default)
			)
			(layer "F.Fab")
		)
		(fp_line
			(start 0.120396 0.3048)
			(end 0.120396 0.2794)
			(stroke
				(width 0.1)
				(type default)
			)
			(layer "F.Fab")
		)
		(fp_line
			(start 0.67945 0.3048)
			(end 0.120396 0.3048)
			(stroke
				(width 0.1)
				(type default)
			)
			(layer "F.Fab")
		)
		(fp_line
			(start -0.12065 0.2794)
			(end -0.12065 0.3048)
			(stroke
				(width 0.1)
				(type default)
			)
			(layer "F.Fab")
		)
		(fp_line
			(start 0.120396 0.2794)
			(end -0.12065 0.2794)
			(stroke
				(width 0.1)
				(type default)
			)
			(layer "F.Fab")
		)
		(fp_line
			(start -0.12065 -0.2794)
			(end 0.12065 -0.2794)
			(stroke
				(width 0.1)
				(type default)
			)
			(layer "F.Fab")
		)
		(fp_line
			(start 0.12065 -0.2794)
			(end 0.12065 -0.3048)
			(stroke
				(width 0.1)
				(type default)
			)
			(layer "F.Fab")
		)
		(fp_line
			(start 0.12065 -0.3048)
			(end 0.67945 -0.3048)
			(stroke
				(width 0.1)
				(type default)
			)
			(layer "F.Fab")
		)
		(fp_line
			(start 0.67945 -0.3048)
			(end 0.67945 0.3048)
			(stroke
				(width 0.1)
				(type default)
			)
			(layer "F.Fab")
		)
		(fp_line
			(start -0.67945 -0.305054)
			(end -0.12065 -0.305054)
			(stroke
				(width 0.1)
				(type default)
			)
			(layer "F.Fab")
		)
		(fp_line
			(start -0.12065 -0.305054)
			(end -0.12065 -0.2794)
			(stroke
				(width 0.1)
				(type default)
			)
			(layer "F.Fab")
		)
		(pad "1" smd circle
			(at -0.40005 0 270)
			(size 0 0)
			(layers "F.Cu" "F.Mask" "F.Paste")
			(net "P3V3_AUX")
		)
		(pad "2" smd circle
			(at 0.40005 0 270)
			(size 0 0)
			(layers "F.Cu" "F.Mask" "F.Paste")
			(net "GPU_WP_HW_CTRL_N")
		)
	)
	(footprint ""
		(layer "F.Cu")
		(at 110.365794 -385.58216)
		(property "Reference" "R916"
			(at 0 0 0)
			(layer "F.SilkS")
			(hide yes)
			(effects
				(font
					(size 1.27 1.27)
				)
			)
		)
		(property "Value" ""
			(at 0 0 0)
			(layer "F.Fab")
			(effects
				(font
					(size 1.27 1.27)
				)
			)
		)
		(duplicate_pad_numbers_are_jumpers no)
		(fp_line
			(start -0.32512 -0.175006)
			(end 0.32512 -0.175006)
			(stroke
				(width 0.1)
				(type default)
			)
			(layer "F.Fab")
		)
		(fp_line
			(start -0.32512 0.175006)
			(end -0.32512 -0.175006)
			(stroke
				(width 0.1)
				(type default)
			)
			(layer "F.Fab")
		)
		(fp_line
			(start 0.32512 -0.175006)
			(end 0.32512 0.175006)
			(stroke
				(width 0.1)
				(type default)
			)
			(layer "F.Fab")
		)
		(fp_line
			(start 0.32512 0.175006)
			(end -0.32512 0.175006)
			(stroke
				(width 0.1)
				(type default)
			)
			(layer "F.Fab")
		)
		(pad "1" smd rect
			(at -0.2667 0)
			(size 0.3048 0.381)
			(layers "F.Cu" "F.Mask" "F.Paste")
			(net "GPIO2_RT_CPU1_P3")
		)
		(pad "2" smd rect
			(at 0.2667 0 180)
			(size 0.3048 0.381)
			(layers "F.Cu" "F.Mask" "F.Paste")
			(net "GND")
		)
	)
)
